FILE_TYPE = CONNECTIVITY;
{Allegro Design Entry HDL 17.2-2016 S081 (4005846) 1/11/2022}
"PAGE_NUMBER" = 218;
0"NC";
1"PVNN_TERM_CPU1\g";
2"P3V3_AUX\g";
3"GND\g";
4"GND\g";
5"GND\g";
6"I3C_SPD_DDRABCD_CPU1_LVC1_SCL";
7"I3C_SPD_DDRABCD_CPU1_LVC1_SDA";
8"I3C_SPD_DDREFGH_CPU1_LVC1_SCL";
9"I3C_SPD_DDREFGH_CPU1_LVC1_SDA";
10"I3C_SPD_DDRABCD_CPU1_R_SCL";
11"I3C_SPD_DDRABCD_CPU1_R_SDA";
12"I3C_SPD_DDREFGH_CPU1_R_SCL";
13"I3C_SPD_DDREFGH_CPU1_R_SDA";
14"I3C_SPD_DDRABCD_CPU1_LVC1_R_SCL";
15"I3C_SPD_DDRABCD_CPU1_LVC1_R_SDA";
16"I3C_SPD_DDREFGH_CPU1_LVC1_R_SCL";
17"I3C_SPD_DDREFGH_CPU1_LVC1_R_SDA";
18"I3C_SPD_DDREFGH_CPU1_SDA";
19"I3C_SPD_DDREFGH_CPU1_SCL";
20"I3C_SPD_DDRABCD_CPU1_SCL";
21"I3C_SPD_DDRABCD_CPU1_SDA";
22"I3C_SPD_DDREFGH_CPU1_R_SDA";
23"I3C_SPD_DDREFGH_CPU1_R_SCL";
24"I3C_SPD_DDRABCD_CPU1_R_SCL";
25"I3C_SPD_DDRABCD_CPU1_R_SDA";
26"I3C_SPD_DDRABCD_CPU1_BMC_SDA";
27"I3C_SPD_DDREFGH_CPU1_BMC_SDA";
28"I3C_SPD_DDRABCD_CPU1_BMC_SCL";
29"FM_SPD_REMOTE_EN";
30"I3C_SPD_DDREFGH_CPU1_BMC_SCL";
31"PD_I3C_SPD_DDR_CPU1_OE_N";
%"QS3VH257QG8"
"1","(650,1750)","2","pure_quanta","I12";
;
PART_NUMBER"AL000257W24"
PACK_TYPE"SMLF"
VALUE"QS3VH257QG8"
MATERIAL"IC"
LOCATION"U14"
NEEDS_NO_SIZE"TRUE"
CDS_LMAN_SYM_OUTLINE"-150,375,150,-375"
CDS_LIB"pure_quanta"
$SEC"1"
CDS_SEC"1";
"I1D"
$PN"13"27;
"I0D"
$PN"14"22;
"YD"
$PN"12"17;
"YC"
$PN"9"16;
"I1C"
$PN"10"30;
"I0C"
$PN"11"23;
"YB"
$PN"7"15;
"I1B"
$PN"6"26;
"I0B"
$PN"5"25;
"I1A"
$PN"3"28;
"I0A"
$PN"2"24;
"VCC"
$PN"16"2;
"GND"
$PN"8"4;
"YA"
$PN"4"14;
"E*"
$PN"15"31;
"S"
$PN"1"29;
%"Q_RES"
"2","(-25,4300)","0","pure_quanta","I17";
;
PART_NUMBER"CS14992FB06"
PACK_TYPE"0402LF"
WATTAGE"1/16W"
MATERIAL"CHIP"
TOLERANCE"1%"
VALUE"499"
$LOCATION"R662"
CDS_LIB"pure_quanta"
CDS_LOCATION"R662"
$SEC"1"
CDS_SEC"1";
"A"
$PN"1"1;
"B"
$PN"2"20;
%"Q_RES"
"2","(225,4300)","0","pure_quanta","I18";
;
PART_NUMBER"CS14992FB06"
TOLERANCE"1%"
MATERIAL"CHIP"
WATTAGE"1/16W"
PACK_TYPE"0402LF"
VALUE"499"
$LOCATION"R663"
CDS_LIB"pure_quanta"
CDS_LOCATION"R663"
$SEC"1"
CDS_SEC"1";
"A"
$PN"1"1;
"B"
$PN"2"21;
%"UNIVERSAL_POWER"
"1","(-25,4675)","0","logical_power","I19";
;
HDL_POWER"PVNN_TERM_CPU1"
CDS_LIB"logical_power";
"A"1;
%"Q_RES"
"1","(625,775)","0","pure_quanta","I20";
;
PART_NUMBER"CS00002JB13"
WATTAGE"1/16W"
PACK_TYPE"0402LF"
TOLERANCE"5%"
VALUE"0"
MATERIAL"EMPTY"
$LOCATION"R668"
CDS_LIB"pure_quanta"
CDS_LOCATION"R668"
$SEC"1"
CDS_SEC"1";
"B"
$PN"2"17;
"A"
$PN"1"22;
%"Q_RES"
"1","(625,900)","0","pure_quanta","I21";
;
PART_NUMBER"CS00002JB13"
MATERIAL"EMPTY"
PACK_TYPE"0402LF"
WATTAGE"1/16W"
VALUE"0"
TOLERANCE"5%"
$LOCATION"R667"
CDS_LIB"pure_quanta"
CDS_LOCATION"R667"
$SEC"1"
CDS_SEC"1";
"B"
$PN"2"16;
"A"
$PN"1"23;
%"Q_RES"
"1","(625,1025)","0","pure_quanta","I22";
;
PART_NUMBER"CS00002JB13"
VALUE"0"
TOLERANCE"5%"
PACK_TYPE"0402LF"
WATTAGE"1/16W"
MATERIAL"EMPTY"
$LOCATION"R666"
CDS_LIB"pure_quanta"
CDS_LOCATION"R666"
$SEC"1"
CDS_SEC"1";
"B"
$PN"2"15;
"A"
$PN"1"25;
%"Q_RES"
"1","(625,1150)","0","pure_quanta","I23";
;
PART_NUMBER"CS00002JB13"
PACK_TYPE"0402LF"
WATTAGE"1/16W"
VALUE"0"
TOLERANCE"5%"
MATERIAL"EMPTY"
$LOCATION"R665"
CDS_LIB"pure_quanta"
CDS_LOCATION"R665"
$SEC"1"
CDS_SEC"1";
"B"
$PN"2"14;
"A"
$PN"1"24;
%"UNIVERSAL_GND"
"1","(1025,1300)","0","logical_power","I24";
;
HDL_POWER"GND"
CDS_LIB"logical_power";
"A"4;
%"Q_CAP"
"1","(1250,2350)","0","pure_quanta","I25";
;
PART_NUMBER"CH4104K1B00"
VALUE"0.1UF"
TOLERANCE"10%"
MATERIAL"X7R"
PACK_TYPE"0402"
VOLTAGE"25V"
$LOCATION"C537"
CDS_LIB"pure_quanta"
CDS_LOCATION"C537"
$SEC"1"
CDS_SEC"1";
"B"
$PN"2"5;
"A"
$PN"1"2;
%"UNIVERSAL_GND"
"1","(1250,2100)","0","logical_power","I26";
;
HDL_POWER"GND"
CDS_LIB"logical_power";
"A"5;
%"UNIVERSAL_POWER"
"1","(1025,2675)","0","logical_power","I27";
;
HDL_POWER"P3V3_AUX"
CDS_LIB"logical_power";
"A"2;
%"Q_RES"
"2","(475,4300)","0","pure_quanta","I28";
;
PART_NUMBER"CS14992FB06"
TOLERANCE"1%"
MATERIAL"CHIP"
WATTAGE"1/16W"
PACK_TYPE"0402LF"
VALUE"499"
$LOCATION"R664"
CDS_LIB"pure_quanta"
CDS_LOCATION"R664"
$SEC"1"
CDS_SEC"1";
"A"
$PN"1"1;
"B"
$PN"2"19;
%"Q_RES"
"2","(725,4300)","0","pure_quanta","I29";
;
PART_NUMBER"CS14992FB06"
WATTAGE"1/16W"
MATERIAL"CHIP"
TOLERANCE"1%"
VALUE"499"
PACK_TYPE"0402LF"
$LOCATION"R669"
CDS_LIB"pure_quanta"
CDS_LOCATION"R669"
$SEC"1"
CDS_SEC"1";
"A"
$PN"1"1;
"B"
$PN"2"18;
%"UNIVERSAL_GND"
"1","(-1050,1000)","0","logical_power","I3";
;
HDL_POWER"GND"
CDS_LIB"logical_power";
"A"3;
%"Q_RES"
"1","(1125,3675)","0","pure_quanta","I30";
;
PART_NUMBER"CS00002JB13"
PACK_TYPE"0402LF"
TOLERANCE"5%"
MATERIAL"CHIP"
WATTAGE"1/16W"
VALUE"0"
LOCATION"R672"
CDS_LIB"pure_quanta"
$SEC"1"
CDS_SEC"1";
"B"
$PN"2"12;
"A"
$PN"1"19;
%"Q_RES"
"1","(1125,3625)","0","pure_quanta","I31";
;
PART_NUMBER"CS03322FB03"
VALUE"33.2"
PACK_TYPE"0402LF"
TOLERANCE"1%"
$LOCATION"R673"
CDS_LIB"pure_quanta"
MATERIAL"CHIP"
WATTAGE"1/16W"
CDS_LOCATION"R673"
$SEC"1"
CDS_SEC"1";
"B"
$PN"2"13;
"A"
$PN"1"18;
%"Q_RES"
"1","(1125,3975)","0","pure_quanta","I32";
;
PART_NUMBER"CS00002JB13"
VALUE"0"
PACK_TYPE"0402LF"
WATTAGE"1/16W"
MATERIAL"CHIP"
TOLERANCE"5%"
LOCATION"R670"
CDS_LIB"pure_quanta"
$SEC"1"
CDS_SEC"1";
"B"
$PN"2"10;
"A"
$PN"1"20;
%"Q_RES"
"1","(1125,3925)","0","pure_quanta","I33";
;
PART_NUMBER"CS03322FB03"
VALUE"33.2"
PACK_TYPE"0402LF"
TOLERANCE"1%"
$LOCATION"R671"
CDS_LIB"pure_quanta"
WATTAGE"1/16W"
MATERIAL"CHIP"
CDS_LOCATION"R671"
$SEC"1"
CDS_SEC"1";
"B"
$PN"2"11;
"A"
$PN"1"21;
%"Q_RES"
"1","(2750,1575)","0","pure_quanta","I34";
;
PART_NUMBER"CS03322FB03"
VALUE"33.2"
TOLERANCE"1%"
$LOCATION"R677"
PACK_TYPE"0402LF"
MATERIAL"CHIP"
WATTAGE"1/16W"
CDS_LIB"pure_quanta"
CDS_LOCATION"R677"
$SEC"1"
CDS_SEC"1";
"B"
$PN"2"9;
"A"
$PN"1"17;
%"Q_RES"
"1","(2750,1725)","0","pure_quanta","I35";
;
PART_NUMBER"CS00002JB13"
TOLERANCE"5%"
VALUE"0"
$LOCATION"R676"
MATERIAL"CHIP"
WATTAGE"1/16W"
CDS_LIB"pure_quanta"
PACK_TYPE"0402LF"
CDS_LOCATION"R676"
$SEC"1"
CDS_SEC"1";
"B"
$PN"2"8;
"A"
$PN"1"16;
%"Q_RES"
"1","(2750,1875)","0","pure_quanta","I36";
;
PART_NUMBER"CS03322FB03"
VALUE"33.2"
TOLERANCE"1%"
$LOCATION"R675"
PACK_TYPE"0402LF"
CDS_LIB"pure_quanta"
WATTAGE"1/16W"
MATERIAL"CHIP"
CDS_LOCATION"R675"
$SEC"1"
CDS_SEC"1";
"B"
$PN"2"7;
"A"
$PN"1"15;
%"Q_RES"
"1","(2750,2025)","0","pure_quanta","I37";
;
PART_NUMBER"CS00002JB13"
MATERIAL"CHIP"
PACK_TYPE"0402LF"
WATTAGE"1/16W"
VALUE"0"
TOLERANCE"5%"
$LOCATION"R674"
CDS_LIB"pure_quanta"
CDS_LOCATION"R674"
$SEC"1"
CDS_SEC"1";
"B"
$PN"2"6;
"A"
$PN"1"14;
%"Q_RES"
"2","(-1050,1225)","0","pure_quanta","I4";
;
PART_NUMBER"CS21002FB06"
WATTAGE"1/16W"
MATERIAL"CHIP"
PACK_TYPE"0402LF"
VALUE"1K"
TOLERANCE"1%"
$LOCATION"R661"
CDS_LIB"pure_quanta"
CDS_LOCATION"R661"
$SEC"1"
CDS_SEC"1";
"A"
$PN"1"31;
"B"
$PN"2"3;
END.
